(kicad_pcb
	(version 20260206)
	(generator "pcbnew")
	(generator_version "10.0")
	(general
		(thickness 1.6)
		(legacy_teardrops no)
	)
	(paper "A4")
	(title_block
		(title "01162023_DA0F0TEBIF0_F0T_Expander_BD_F_brd_V02_OCP.brd")
		(comment 1 "Grand Teton / footprint 6602 of 9728 (PEX1), pads 2000-2119 of 2397")
	)
	(layers
		(0 "F.Cu" signal "TOP")
		(4 "In1.Cu" signal "GND")
		(6 "In2.Cu" signal "VCC")
		(8 "In3.Cu" signal "VCC1")
		(10 "In4.Cu" signal "GND1")
		(12 "In5.Cu" signal "IN1")
		(14 "In6.Cu" signal "GND2")
		(16 "In7.Cu" signal "IN2")
		(18 "In8.Cu" signal "GND3")
		(20 "In9.Cu" signal "IN3")
		(22 "In10.Cu" signal "GND4")
		(24 "In11.Cu" signal "IN4")
		(26 "In12.Cu" signal "GND5")
		(28 "In13.Cu" signal "IN5")
		(30 "In14.Cu" signal "GND6")
		(32 "In15.Cu" signal "IN6")
		(34 "In16.Cu" signal "GND7")
		(2 "B.Cu" signal "BOTTOM")
		(9 "F.Adhes" user "F.Adhesive")
		(11 "B.Adhes" user "B.Adhesive")
		(13 "F.Paste" user "Package Geometry/Pastemask Top")
		(15 "B.Paste" user "Package Geometry/Pastemask Bottom")
		(5 "F.SilkS" user "Ref Des/Silkscreen Top")
		(7 "B.SilkS" user "Ref Des/Silkscreen Bottom")
		(1 "F.Mask" user "Board Geometry/Soldermask Top")
		(3 "B.Mask" user "Board Geometry/Soldermask Bottom")
		(17 "Dwgs.User" user "User.Drawings")
		(19 "Cmts.User" user "User.Comments")
		(21 "Eco1.User" user "User.Eco1")
		(23 "Eco2.User" user "User.Eco2")
		(25 "Edge.Cuts" user "Board Geometry/Outline")
		(27 "Margin" user)
		(31 "F.CrtYd" user "Package Geometry/Place Bound Top")
		(29 "B.CrtYd" user "Package Geometry/Place Bound Bottom")
		(35 "F.Fab" user "Ref Des/Assembly Top")
		(33 "B.Fab" user "Ref Des/Assembly Bottom")
	)
	(footprint ""
		(layer "F.Cu")
		(at 175.749966 -295.89984)
		(property "Reference" "PEX1"
			(at -3.353562 35.593274 0)
			(unlocked yes)
			(layer "F.SilkS")
			(effects
				(font
					(size 2.032 1.524)
					(thickness 0.1524)
				)
				(justify left)
			)
		)
		(property "Value" ""
			(at 0 0 0)
			(layer "F.Fab")
			(effects
				(font
					(size 1.27 1.27)
				)
			)
		)
		(duplicate_pad_numbers_are_jumpers no)
		(pad "M44" smd circle
			(at 18.050002 -12.349988)
			(size 0.4572 0.4572)
			(layers "F.Cu" "F.Mask" "F.Paste")
			(net "GND")
		)
		(pad "M45" smd circle
			(at 18.999962 -12.349988)
			(size 0.4572 0.4572)
			(layers "F.Cu" "F.Mask" "F.Paste")
			(net "GND")
		)
		(pad "M46" smd circle
			(at 19.949922 -12.349988)
			(size 0.4572 0.4572)
			(layers "F.Cu" "F.Mask" "F.Paste")
			(net "GND")
		)
		(pad "M47" smd circle
			(at 20.899882 -12.349988)
			(size 0.4572 0.4572)
			(layers "F.Cu" "F.Mask" "F.Paste")
			(net "GND")
		)
		(pad "M48" smd circle
			(at 21.850096 -12.349988)
			(size 0.4572 0.4572)
			(layers "F.Cu" "F.Mask" "F.Paste")
			(net "P5E_PEX1_STN4_RX_DP<68>")
		)
		(pad "M49" smd circle
			(at 22.800056 -12.349988)
			(size 0.4572 0.4572)
			(layers "F.Cu" "F.Mask" "F.Paste")
			(net "P5E_PEX1_STN4_RX_DN<68>")
		)
		(pad "N1" smd circle
			(at -22.800056 -11.400028)
			(size 0.4572 0.4572)
			(layers "F.Cu" "F.Mask" "F.Paste")
			(net "GND")
		)
		(pad "N2" smd circle
			(at -21.850096 -11.400028)
			(size 0.4572 0.4572)
			(layers "F.Cu" "F.Mask" "F.Paste")
			(net "GND")
		)
		(pad "N3" smd circle
			(at -20.899882 -11.400028)
			(size 0.4572 0.4572)
			(layers "F.Cu" "F.Mask" "F.Paste")
			(net "P5E_PEX1_STN7_RX_DN<118>")
		)
		(pad "N4" smd circle
			(at -19.949922 -11.400028)
			(size 0.4572 0.4572)
			(layers "F.Cu" "F.Mask" "F.Paste")
			(net "P5E_PEX1_STN7_RX_DP<118>")
		)
		(pad "N5" smd circle
			(at -18.999962 -11.400028)
			(size 0.4572 0.4572)
			(layers "F.Cu" "F.Mask" "F.Paste")
			(net "GND")
		)
		(pad "N6" smd circle
			(at -18.050002 -11.400028)
			(size 0.4572 0.4572)
			(layers "F.Cu" "F.Mask" "F.Paste")
			(net "P5E_PEX1_STN7_TX_DN<118>")
		)
		(pad "N7" smd circle
			(at -17.100042 -11.400028)
			(size 0.4572 0.4572)
			(layers "F.Cu" "F.Mask" "F.Paste")
			(net "P5E_PEX1_STN7_TX_DP<118>")
		)
		(pad "N8" smd circle
			(at -16.150082 -11.400028)
			(size 0.4572 0.4572)
			(layers "F.Cu" "F.Mask" "F.Paste")
			(net "GND")
		)
		(pad "N9" smd circle
			(at -15.200122 -11.400028)
			(size 0.4572 0.4572)
			(layers "F.Cu" "F.Mask" "F.Paste")
			(net "GND")
		)
		(pad "N10" smd circle
			(at -14.249908 -11.400028)
			(size 0.4572 0.4572)
			(layers "F.Cu" "F.Mask" "F.Paste")
			(net "GND")
		)
		(pad "N11" smd circle
			(at -13.299948 -11.400028)
			(size 0.4572 0.4572)
			(layers "F.Cu" "F.Mask" "F.Paste")
			(net "GND")
		)
		(pad "N12" smd circle
			(at -12.349988 -11.400028)
			(size 0.4572 0.4572)
			(layers "F.Cu" "F.Mask" "F.Paste")
			(net "GND")
		)
		(pad "N13" smd circle
			(at -11.400028 -11.400028)
			(size 0.4572 0.4572)
			(layers "F.Cu" "F.Mask" "F.Paste")
			(net "GND")
		)
		(pad "N14" smd circle
			(at -10.450068 -11.400028)
			(size 0.4572 0.4572)
			(layers "F.Cu" "F.Mask" "F.Paste")
			(net "GND")
		)
		(pad "N15" smd circle
			(at -9.500108 -11.400028)
			(size 0.4572 0.4572)
			(layers "F.Cu" "F.Mask" "F.Paste")
			(net "GND")
		)
		(pad "N16" smd circle
			(at -8.549894 -11.400028)
			(size 0.4572 0.4572)
			(layers "F.Cu" "F.Mask" "F.Paste")
			(net "GND")
		)
		(pad "N17" smd circle
			(at -7.599934 -11.400028)
			(size 0.4572 0.4572)
			(layers "F.Cu" "F.Mask" "F.Paste")
			(net "GND")
		)
		(pad "N18" smd circle
			(at -6.649974 -11.400028)
			(size 0.4572 0.4572)
			(layers "F.Cu" "F.Mask" "F.Paste")
			(net "GND")
		)
		(pad "N19" smd circle
			(at -5.700014 -11.400028)
			(size 0.4572 0.4572)
			(layers "F.Cu" "F.Mask" "F.Paste")
			(net "GND")
		)
		(pad "N20" smd circle
			(at -4.750054 -11.400028)
			(size 0.4572 0.4572)
			(layers "F.Cu" "F.Mask" "F.Paste")
			(net "GND")
		)
		(pad "N21" smd circle
			(at -3.800094 -11.400028)
			(size 0.4572 0.4572)
			(layers "F.Cu" "F.Mask" "F.Paste")
			(net "GND")
		)
		(pad "N22" smd circle
			(at -2.84988 -11.400028)
			(size 0.4572 0.4572)
			(layers "F.Cu" "F.Mask" "F.Paste")
			(net "GND")
		)
		(pad "N23" smd circle
			(at -1.89992 -11.400028)
			(size 0.4572 0.4572)
			(layers "F.Cu" "F.Mask" "F.Paste")
			(net "GND")
		)
		(pad "N24" smd circle
			(at -0.94996 -11.400028)
			(size 0.4572 0.4572)
			(layers "F.Cu" "F.Mask" "F.Paste")
			(net "GND")
		)
		(pad "N25" smd circle
			(at 0 -11.400028)
			(size 0.4572 0.4572)
			(layers "F.Cu" "F.Mask" "F.Paste")
			(net "GND")
		)
		(pad "N26" smd circle
			(at 0.94996 -11.400028)
			(size 0.4572 0.4572)
			(layers "F.Cu" "F.Mask" "F.Paste")
			(net "GND")
		)
		(pad "N27" smd circle
			(at 1.89992 -11.400028)
			(size 0.4572 0.4572)
			(layers "F.Cu" "F.Mask" "F.Paste")
			(net "GND")
		)
		(pad "N28" smd circle
			(at 2.84988 -11.400028)
			(size 0.4572 0.4572)
			(layers "F.Cu" "F.Mask" "F.Paste")
			(net "GND")
		)
		(pad "N29" smd circle
			(at 3.800094 -11.400028)
			(size 0.4572 0.4572)
			(layers "F.Cu" "F.Mask" "F.Paste")
			(net "GND")
		)
		(pad "N30" smd circle
			(at 4.750054 -11.400028)
			(size 0.4572 0.4572)
			(layers "F.Cu" "F.Mask" "F.Paste")
			(net "GND")
		)
		(pad "N31" smd circle
			(at 5.700014 -11.400028)
			(size 0.4572 0.4572)
			(layers "F.Cu" "F.Mask" "F.Paste")
			(net "GND")
		)
		(pad "N32" smd circle
			(at 6.649974 -11.400028)
			(size 0.4572 0.4572)
			(layers "F.Cu" "F.Mask" "F.Paste")
			(net "GND")
		)
		(pad "N33" smd circle
			(at 7.599934 -11.400028)
			(size 0.4572 0.4572)
			(layers "F.Cu" "F.Mask" "F.Paste")
			(net "GND")
		)
		(pad "N34" smd circle
			(at 8.549894 -11.400028)
			(size 0.4572 0.4572)
			(layers "F.Cu" "F.Mask" "F.Paste")
			(net "GND")
		)
		(pad "N35" smd circle
			(at 9.500108 -11.400028)
			(size 0.4572 0.4572)
			(layers "F.Cu" "F.Mask" "F.Paste")
			(net "GND")
		)
		(pad "N36" smd circle
			(at 10.450068 -11.400028)
			(size 0.4572 0.4572)
			(layers "F.Cu" "F.Mask" "F.Paste")
			(net "GND")
		)
		(pad "N37" smd circle
			(at 11.400028 -11.400028)
			(size 0.4572 0.4572)
			(layers "F.Cu" "F.Mask" "F.Paste")
			(net "GND")
		)
		(pad "N38" smd circle
			(at 12.349988 -11.400028)
			(size 0.4572 0.4572)
			(layers "F.Cu" "F.Mask" "F.Paste")
			(net "SMB_PEX1_SLAVE_SCL")
		)
		(pad "N39" smd circle
			(at 13.299948 -11.400028)
			(size 0.4572 0.4572)
			(layers "F.Cu" "F.Mask" "F.Paste")
			(net "Net_5280")
		)
		(pad "N40" smd circle
			(at 14.249908 -11.400028)
			(size 0.4572 0.4572)
			(layers "F.Cu" "F.Mask" "F.Paste")
			(net "GND")
		)
		(pad "N41" smd circle
			(at 15.200122 -11.400028)
			(size 0.4572 0.4572)
			(layers "F.Cu" "F.Mask" "F.Paste")
			(net "GND")
		)
		(pad "N42" smd circle
			(at 16.150082 -11.400028)
			(size 0.4572 0.4572)
			(layers "F.Cu" "F.Mask" "F.Paste")
			(net "GND")
		)
		(pad "N43" smd circle
			(at 17.100042 -11.400028)
			(size 0.4572 0.4572)
			(layers "F.Cu" "F.Mask" "F.Paste")
			(net "P5E_PEX1_STN4_TX_DP<67>")
		)
		(pad "N44" smd circle
			(at 18.050002 -11.400028)
			(size 0.4572 0.4572)
			(layers "F.Cu" "F.Mask" "F.Paste")
			(net "P5E_PEX1_STN4_TX_DN<67>")
		)
		(pad "N45" smd circle
			(at 18.999962 -11.400028)
			(size 0.4572 0.4572)
			(layers "F.Cu" "F.Mask" "F.Paste")
			(net "GND")
		)
		(pad "N46" smd circle
			(at 19.949922 -11.400028)
			(size 0.4572 0.4572)
			(layers "F.Cu" "F.Mask" "F.Paste")
			(net "P5E_PEX1_STN4_RX_DP<67>")
		)
		(pad "N47" smd circle
			(at 20.899882 -11.400028)
			(size 0.4572 0.4572)
			(layers "F.Cu" "F.Mask" "F.Paste")
			(net "P5E_PEX1_STN4_RX_DN<67>")
		)
		(pad "N48" smd circle
			(at 21.850096 -11.400028)
			(size 0.4572 0.4572)
			(layers "F.Cu" "F.Mask" "F.Paste")
			(net "GND")
		)
		(pad "N49" smd circle
			(at 22.800056 -11.400028)
			(size 0.4572 0.4572)
			(layers "F.Cu" "F.Mask" "F.Paste")
			(net "GND")
		)
		(pad "P1" smd circle
			(at -22.800056 -10.450068)
			(size 0.4572 0.4572)
			(layers "F.Cu" "F.Mask" "F.Paste")
			(net "P5E_PEX1_STN7_RX_DN<117>")
		)
		(pad "P2" smd circle
			(at -21.850096 -10.450068)
			(size 0.4572 0.4572)
			(layers "F.Cu" "F.Mask" "F.Paste")
			(net "P5E_PEX1_STN7_RX_DP<117>")
		)
		(pad "P3" smd circle
			(at -20.899882 -10.450068)
			(size 0.4572 0.4572)
			(layers "F.Cu" "F.Mask" "F.Paste")
			(net "GND")
		)
		(pad "P4" smd circle
			(at -19.949922 -10.450068)
			(size 0.4572 0.4572)
			(layers "F.Cu" "F.Mask" "F.Paste")
			(net "GND")
		)
		(pad "P5" smd circle
			(at -18.999962 -10.450068)
			(size 0.4572 0.4572)
			(layers "F.Cu" "F.Mask" "F.Paste")
			(net "GND")
		)
		(pad "P6" smd circle
			(at -18.050002 -10.450068)
			(size 0.4572 0.4572)
			(layers "F.Cu" "F.Mask" "F.Paste")
			(net "GND")
		)
		(pad "P7" smd circle
			(at -17.100042 -10.450068)
			(size 0.4572 0.4572)
			(layers "F.Cu" "F.Mask" "F.Paste")
			(net "GND")
		)
		(pad "P8" smd circle
			(at -16.150082 -10.450068)
			(size 0.4572 0.4572)
			(layers "F.Cu" "F.Mask" "F.Paste")
			(net "P5E_PEX1_STN7_TX_DN<117>")
		)
		(pad "P9" smd circle
			(at -15.200122 -10.450068)
			(size 0.4572 0.4572)
			(layers "F.Cu" "F.Mask" "F.Paste")
			(net "P5E_PEX1_STN7_TX_DP<117>")
		)
		(pad "P10" smd circle
			(at -14.249908 -10.450068)
			(size 0.4572 0.4572)
			(layers "F.Cu" "F.Mask" "F.Paste")
			(net "GND")
		)
		(pad "P11" smd circle
			(at -13.299948 -10.450068)
			(size 0.4572 0.4572)
			(layers "F.Cu" "F.Mask" "F.Paste")
			(net "GND")
		)
		(pad "P12" smd circle
			(at -12.349988 -10.450068)
			(size 0.4572 0.4572)
			(layers "F.Cu" "F.Mask" "F.Paste")
			(net "GND")
		)
		(pad "P13" smd circle
			(at -11.400028 -10.450068)
			(size 0.4572 0.4572)
			(layers "F.Cu" "F.Mask" "F.Paste")
			(net "GND")
		)
		(pad "P14" smd circle
			(at -10.450068 -10.450068)
			(size 0.4572 0.4572)
			(layers "F.Cu" "F.Mask" "F.Paste")
			(net "GND")
		)
		(pad "P15" smd circle
			(at -9.500108 -10.450068)
			(size 0.4572 0.4572)
			(layers "F.Cu" "F.Mask" "F.Paste")
			(net "GND")
		)
		(pad "P16" smd circle
			(at -8.549894 -10.450068)
			(size 0.4572 0.4572)
			(layers "F.Cu" "F.Mask" "F.Paste")
			(net "GND")
		)
		(pad "P17" smd circle
			(at -7.599934 -10.450068)
			(size 0.4572 0.4572)
			(layers "F.Cu" "F.Mask" "F.Paste")
			(net "GND")
		)
		(pad "P18" smd circle
			(at -6.649974 -10.450068)
			(size 0.4572 0.4572)
			(layers "F.Cu" "F.Mask" "F.Paste")
			(net "GND")
		)
		(pad "P19" smd circle
			(at -5.700014 -10.450068)
			(size 0.4572 0.4572)
			(layers "F.Cu" "F.Mask" "F.Paste")
			(net "GND")
		)
		(pad "P20" smd circle
			(at -4.750054 -10.450068)
			(size 0.4572 0.4572)
			(layers "F.Cu" "F.Mask" "F.Paste")
			(net "GND")
		)
		(pad "P21" smd circle
			(at -3.800094 -10.450068)
			(size 0.4572 0.4572)
			(layers "F.Cu" "F.Mask" "F.Paste")
			(net "GND")
		)
		(pad "P22" smd circle
			(at -2.84988 -10.450068)
			(size 0.4572 0.4572)
			(layers "F.Cu" "F.Mask" "F.Paste")
			(net "GND")
		)
		(pad "P23" smd circle
			(at -1.89992 -10.450068)
			(size 0.4572 0.4572)
			(layers "F.Cu" "F.Mask" "F.Paste")
			(net "GND")
		)
		(pad "P24" smd circle
			(at -0.94996 -10.450068)
			(size 0.4572 0.4572)
			(layers "F.Cu" "F.Mask" "F.Paste")
			(net "GND")
		)
		(pad "P25" smd circle
			(at 0 -10.450068)
			(size 0.4572 0.4572)
			(layers "F.Cu" "F.Mask" "F.Paste")
			(net "GND")
		)
		(pad "P26" smd circle
			(at 0.94996 -10.450068)
			(size 0.4572 0.4572)
			(layers "F.Cu" "F.Mask" "F.Paste")
			(net "GND")
		)
		(pad "P27" smd circle
			(at 1.89992 -10.450068)
			(size 0.4572 0.4572)
			(layers "F.Cu" "F.Mask" "F.Paste")
			(net "GND")
		)
		(pad "P28" smd circle
			(at 2.84988 -10.450068)
			(size 0.4572 0.4572)
			(layers "F.Cu" "F.Mask" "F.Paste")
			(net "GND")
		)
		(pad "P29" smd circle
			(at 3.800094 -10.450068)
			(size 0.4572 0.4572)
			(layers "F.Cu" "F.Mask" "F.Paste")
			(net "GND")
		)
		(pad "P30" smd circle
			(at 4.750054 -10.450068)
			(size 0.4572 0.4572)
			(layers "F.Cu" "F.Mask" "F.Paste")
			(net "GND")
		)
		(pad "P31" smd circle
			(at 5.700014 -10.450068)
			(size 0.4572 0.4572)
			(layers "F.Cu" "F.Mask" "F.Paste")
			(net "GND")
		)
		(pad "P32" smd circle
			(at 6.649974 -10.450068)
			(size 0.4572 0.4572)
			(layers "F.Cu" "F.Mask" "F.Paste")
			(net "GND")
		)
		(pad "P33" smd circle
			(at 7.599934 -10.450068)
			(size 0.4572 0.4572)
			(layers "F.Cu" "F.Mask" "F.Paste")
			(net "GND")
		)
		(pad "P34" smd circle
			(at 8.549894 -10.450068)
			(size 0.4572 0.4572)
			(layers "F.Cu" "F.Mask" "F.Paste")
			(net "GND")
		)
		(pad "P35" smd circle
			(at 9.500108 -10.450068)
			(size 0.4572 0.4572)
			(layers "F.Cu" "F.Mask" "F.Paste")
			(net "GND")
		)
		(pad "P36" smd circle
			(at 10.450068 -10.450068)
			(size 0.4572 0.4572)
			(layers "F.Cu" "F.Mask" "F.Paste")
			(net "Net_495")
		)
		(pad "P37" smd circle
			(at 11.400028 -10.450068)
			(size 0.4572 0.4572)
			(layers "F.Cu" "F.Mask" "F.Paste")
			(net "GND")
		)
		(pad "P38" smd circle
			(at 12.349988 -10.450068)
			(size 0.4572 0.4572)
			(layers "F.Cu" "F.Mask" "F.Paste")
			(net "RST_PEX1_S3_PERST_R_N")
		)
		(pad "P39" smd circle
			(at 13.299948 -10.450068)
			(size 0.4572 0.4572)
			(layers "F.Cu" "F.Mask" "F.Paste")
			(net "RST_PEX1_S1_PERST_R_N")
		)
		(pad "P40" smd circle
			(at 14.249908 -10.450068)
			(size 0.4572 0.4572)
			(layers "F.Cu" "F.Mask" "F.Paste")
			(net "GND")
		)
		(pad "P41" smd circle
			(at 15.200122 -10.450068)
			(size 0.4572 0.4572)
			(layers "F.Cu" "F.Mask" "F.Paste")
			(net "P5E_PEX1_STN4_TX_DP<66>")
		)
		(pad "P42" smd circle
			(at 16.150082 -10.450068)
			(size 0.4572 0.4572)
			(layers "F.Cu" "F.Mask" "F.Paste")
			(net "P5E_PEX1_STN4_TX_DN<66>")
		)
		(pad "P43" smd circle
			(at 17.100042 -10.450068)
			(size 0.4572 0.4572)
			(layers "F.Cu" "F.Mask" "F.Paste")
			(net "GND")
		)
		(pad "P44" smd circle
			(at 18.050002 -10.450068)
			(size 0.4572 0.4572)
			(layers "F.Cu" "F.Mask" "F.Paste")
			(net "GND")
		)
		(pad "P45" smd circle
			(at 18.999962 -10.450068)
			(size 0.4572 0.4572)
			(layers "F.Cu" "F.Mask" "F.Paste")
			(net "GND")
		)
		(pad "P46" smd circle
			(at 19.949922 -10.450068)
			(size 0.4572 0.4572)
			(layers "F.Cu" "F.Mask" "F.Paste")
			(net "GND")
		)
		(pad "P47" smd circle
			(at 20.899882 -10.450068)
			(size 0.4572 0.4572)
			(layers "F.Cu" "F.Mask" "F.Paste")
			(net "GND")
		)
		(pad "P48" smd circle
			(at 21.850096 -10.450068)
			(size 0.4572 0.4572)
			(layers "F.Cu" "F.Mask" "F.Paste")
			(net "P5E_PEX1_STN4_RX_DP<66>")
		)
		(pad "P49" smd circle
			(at 22.800056 -10.450068)
			(size 0.4572 0.4572)
			(layers "F.Cu" "F.Mask" "F.Paste")
			(net "P5E_PEX1_STN4_RX_DN<66>")
		)
		(pad "R1" smd circle
			(at -22.800056 -9.500108)
			(size 0.4572 0.4572)
			(layers "F.Cu" "F.Mask" "F.Paste")
			(net "GND")
		)
		(pad "R2" smd circle
			(at -21.850096 -9.500108)
			(size 0.4572 0.4572)
			(layers "F.Cu" "F.Mask" "F.Paste")
			(net "GND")
		)
		(pad "R3" smd circle
			(at -20.899882 -9.500108)
			(size 0.4572 0.4572)
			(layers "F.Cu" "F.Mask" "F.Paste")
			(net "P5E_PEX1_STN7_RX_DN<116>")
		)
		(pad "R4" smd circle
			(at -19.949922 -9.500108)
			(size 0.4572 0.4572)
			(layers "F.Cu" "F.Mask" "F.Paste")
			(net "P5E_PEX1_STN7_RX_DP<116>")
		)
		(pad "R5" smd circle
			(at -18.999962 -9.500108)
			(size 0.4572 0.4572)
			(layers "F.Cu" "F.Mask" "F.Paste")
			(net "GND")
		)
		(pad "R6" smd circle
			(at -18.050002 -9.500108)
			(size 0.4572 0.4572)
			(layers "F.Cu" "F.Mask" "F.Paste")
			(net "P5E_PEX1_STN7_TX_DN<116>")
		)
		(pad "R7" smd circle
			(at -17.100042 -9.500108)
			(size 0.4572 0.4572)
			(layers "F.Cu" "F.Mask" "F.Paste")
			(net "P5E_PEX1_STN7_TX_DP<116>")
		)
		(pad "R8" smd circle
			(at -16.150082 -9.500108)
			(size 0.4572 0.4572)
			(layers "F.Cu" "F.Mask" "F.Paste")
			(net "GND")
		)
		(pad "R9" smd circle
			(at -15.200122 -9.500108)
			(size 0.4572 0.4572)
			(layers "F.Cu" "F.Mask" "F.Paste")
			(net "GND")
		)
		(pad "R10" smd circle
			(at -14.249908 -9.500108)
			(size 0.4572 0.4572)
			(layers "F.Cu" "F.Mask" "F.Paste")
			(net "GND")
		)
		(pad "R11" smd circle
			(at -13.299948 -9.500108)
			(size 0.4572 0.4572)
			(layers "F.Cu" "F.Mask" "F.Paste")
			(net "GND")
		)
		(pad "R12" smd circle
			(at -12.349988 -9.500108)
			(size 0.4572 0.4572)
			(layers "F.Cu" "F.Mask" "F.Paste")
			(net "GND")
		)
		(pad "R13" smd circle
			(at -11.400028 -9.500108)
			(size 0.4572 0.4572)
			(layers "F.Cu" "F.Mask" "F.Paste")
			(net "GND")
		)
		(pad "R14" smd circle
			(at -10.450068 -9.500108)
			(size 0.4572 0.4572)
			(layers "F.Cu" "F.Mask" "F.Paste")
			(net "GND")
		)
		(pad "R15" smd circle
			(at -9.500108 -9.500108)
			(size 0.4572 0.4572)
			(layers "F.Cu" "F.Mask" "F.Paste")
			(net "GND")
		)
		(pad "R16" smd circle
			(at -8.549894 -9.500108)
			(size 0.4572 0.4572)
			(layers "F.Cu" "F.Mask" "F.Paste")
			(net "GND")
		)
	)
)
